FILE_TYPE = CONNECTIVITY;
{Allegro Design Entry HDL 16.6-p007 (v16-6-112F) 10/10/2012}
"PAGE_NUMBER" = 157;
0"NC";
1"P3V3_STBY\g";
2"P3V3\g";
3"GND\g";
4"P3V3_STBY\g";
5"P3V3_STBY\g";
6"GND\g";
7"P3V3_STBY\g";
8"GND\g";
9"GND\g";
10"P3V3_STBY\g";
11"P3V3_STBY\g";
12"GND\g";
13"GND\g";
14"P3V3_STBY\g";
15"P3V3_STBY\g";
16"GND\g";
17"P3V3_STBY\g";
18"RST_BMC_DDR3_BUF_IN_N";
19"RST_BMC_SRST_R2_N";
20"FM_ADR_SMI_GPIO_N";
21"FM_BMC_CPLD_GPO";
22"FM_BMC_CPLD_MP_RST_N";
23"IRQ_MEZZ_LAN_ALERT_N";
24"FP_NMI_BTN_N";
25"FM_MP_PS_FAIL_N";
26"FM_MP_PS_REDUNDANT_LOST_N";
27"H_CPU0_FAST_WAKE_B_N";
28"H_CPU0_FAST_WAKE";
29"H_CPU0_FAST_WAKE_LVT3_N";
30"PWRGD_DSW_PWROK";
31"RST_BMC_SRST_N";
32"FM_TPM_PRES_RST_N";
33"FP_NMI_BTN";
34"FP_NMI_BTN_OUT_R_N";
35"FP_NMI_BTN_R_N";
36"FM_CPLD_BMC_PWRDN_N";
37"FM_BMC_NMI_N";
38"FP_NMI_BTN_N";
39"FM_BMC_ENABLE_N";
40"FP_NMI_BTN_OUT_N";
41"H_CPU0_FAST_WAKE_N";
42"FM_NMI_EVENT_N";
43"FM_BIOS_TOP_SWAP";
44"IRQ_OOB_MGMT_RISER_ALERT_N";
%"RES"
"1","(-7200,4225)","0","mstr_discrete","I296";
;
CDS_SEC"1"
MATERIAL"CHIP"
PACK_TYPE"0402"
TOLERANCE"1%"
VALUE"2.21K"
PART_NUMBER"G21796-112"
WATTAGE"1/16W"
LOCATION"R8F23"
BOM_COST"SM_CONTROLLER"
SEC_TYPE"0402"
SEC"1"
ROOM"BMC_MISC"
CDS_LOCATION"R8F23"
CDS_LIB"mstr_discrete";
"B"
$PN"2"23;
"A"
$PN"1"1;
%"P3V3_STBY"
"1","(-7525,4650)","0","mstr_symbols","I297";
;
CDS_LIB"mstr_symbols"
SIZE"1B"
VOLTAGE"3.3V"
BODY_TYPE"PLUMBING"
HDL_POWER"P3V3_STBY";
"G\NAC"1;
%"RES"
"1","(-7175,3975)","0","mstr_discrete","I298";
;
CDS_SEC"1"
PART_NUMBER"G21796-112"
MATERIAL"CHIP"
WATTAGE"1/16W"
PACK_TYPE"0402"
TOLERANCE"1%"
VALUE"2.21K"
LOCATION"R2T29"
BOM_COST"SM_CONTROLLER"
SEC_TYPE"0402"
SEC"1"
ROOM"BMC_MISC"
CDS_LIB"mstr_discrete"
CDS_LOCATION"R2T29";
"B"
$PN"2"44;
"A"
$PN"1"1;
%"RES"
"1","(-2050,3825)","0","mstr_discrete","I302";
;
CDS_SEC"1"
MATERIAL"CHIP"
WATTAGE"1/16W"
PART_NUMBER"G21796-208"
VALUE"51.1"
LOCATION"R2N25"
TOLERANCE"1.0%"
PACK_TYPE"0402"
BOM_COST"SM_CONTROLLER"
ROOM"BMC_MISC"
CDS_LOCATION"R2N25"
SEC"1"
SEC_TYPE"0402"
CDS_LIB"mstr_discrete";
"B"
$PN"2"37;
"A"
$PN"1"42;
%"P3V3"
"1","(-1850,4275)","0","mstr_symbols","I303";
;
BODY_TYPE"PLUMBING"
CDS_LIB"mstr_symbols"
SIZE"1B"
VOLTAGE"3.3V"
HDL_POWER"P3V3";
"G\NAC"2;
%"RES"
"1","(-7175,3725)","0","mstr_discrete","I316";
;
CDS_SEC"1"
MATERIAL"CHIP"
PACK_TYPE"0402"
TOLERANCE"1%"
PART_NUMBER"G21796-072"
VALUE"4.75K"
WATTAGE"1/16W"
LOCATION"R8F24"
BOM_COST"SM_CONTROLLER"
SEC"1"
SEC_TYPE"0402"
ROOM"BMC_MISC"
CDS_LIB"mstr_discrete"
CDS_LOCATION"R8F24";
"B"
$PN"2"24;
"A"
$PN"1"1;
%"GND"
"1","(-6150,525)","0","mstr_symbols","I322";
;
BODY_TYPE"PLUMBING"
SIZE"1B"
VOLTAGE"0.0V"
CDS_LIB"mstr_symbols"
HDL_POWER"GND";
"A\NAC"3;
%"RES"
"2","(-6150,1250)","0","mstr_discrete","I326";
;
CDS_SEC"1"
PACK_TYPE"0402"
PART_NUMBER"G21796-026"
MATERIAL"CHIP"
WATTAGE"1/16W"
TOLERANCE"1%"
VALUE"1.00K"
LOCATION"R2T5"
CDS_LIB"mstr_discrete"
CDS_LOCATION"R2T5"
ROOM"PROC_SIDEBAND"
SEC"1"
SEC_TYPE"0402"
BOM_COST"PROC_SIDEBAND";
"A"
$PN"1"4;
"B"
$PN"2"28;
%"RES"
"2","(-5500,1650)","0","mstr_discrete","I327";
;
CDS_SEC"1"
PACK_TYPE"0402"
PART_NUMBER"G21796-026"
MATERIAL"CHIP"
WATTAGE"1/16W"
TOLERANCE"1%"
VALUE"1.00K"
LOCATION"R2T7"
CDS_LIB"mstr_discrete"
CDS_LOCATION"R2T7"
ROOM"PROC_SIDEBAND"
SEC"1"
SEC_TYPE"0402"
BOM_COST"PROC_SIDEBAND";
"A"
$PN"1"5;
"B"
$PN"2"29;
%"P3V3_STBY"
"1","(-6150,1450)","0","mstr_symbols","I328";
;
HDL_POWER"P3V3_STBY"
BODY_TYPE"PLUMBING"
VOLTAGE"3.3V"
SIZE"1B"
CDS_LIB"mstr_symbols";
"G\NAC"4;
%"P3V3_STBY"
"1","(-5500,1875)","0","mstr_symbols","I329";
;
HDL_POWER"P3V3_STBY"
BODY_TYPE"PLUMBING"
SIZE"1B"
CDS_LIB"mstr_symbols"
VOLTAGE"3.3V";
"G\NAC"5;
%"NPN"
"1","(-6200,775)","0","mstr_discrete","I330";
;
CDS_SEC"1"
VALUE"MMBT3904"
LOCATION"Q2T1"
MATERIAL"IC"
PACK_TYPE"SM"
PART_NUMBER"C52245-001"
CDS_LIB"mstr_discrete"
ROOM"PROC_SIDEBAND"
CDS_LOCATION"Q2T1"
SEC"1"
SEC_TYPE"SM"
BOM_COST"PROC_SIDEBAND";
"C"
$PN"3"28;
"E"
$PN"2"3;
"B"
$PN"1"27;
%"GND"
"1","(-5500,775)","0","mstr_symbols","I333";
;
BODY_TYPE"PLUMBING"
SIZE"1B"
VOLTAGE"0.0V"
HDL_POWER"GND"
CDS_LIB"mstr_symbols";
"A\NAC"6;
%"RES"
"2","(-2275,1525)","0","mstr_discrete","I335";
;
CDS_SEC"1"
PART_NUMBER"G21796-072"
PACK_TYPE"0402"
MATERIAL"CHIP"
WATTAGE"1/16W"
TOLERANCE"1%"
VALUE"4.75K"
LOCATION"R8D25"
CDS_LIB"mstr_discrete"
CDS_LOCATION"R8D25"
SEC"1"
SEC_TYPE"0402"
ROOM"BMC_MISC"
BOM_COST"SM_CONTROLLER";
"A"
$PN"1"7;
"B"
$PN"2"19;
%"P3V3_STBY"
"1","(-2275,1725)","0","mstr_symbols","I339";
;
HDL_POWER"P3V3_STBY"
VOLTAGE"3.3V"
BODY_TYPE"PLUMBING"
CDS_LIB"mstr_symbols"
SIZE"1B";
"G\NAC"7;
%"FET_N"
"8","(-5500,1100)","0","mstr_discrete","I340";
;
CDS_SEC"1"
MATERIAL"FET"
VALUE"2N7002"
LOCATION"Q2T2"
PART_NUMBER"C79254-001"
PACK_TYPE"SOT23LF"
CDS_LIB"mstr_discrete"
ROOM"PROC_SIDEBAND"
CDS_LOCATION"Q2T2"
SEC"1"
BOM_COST"PROC_SIDEBAND"
SEC_TYPE"SOT23LF";
"GATE"
$PN"1"28;
"DRN"
$PN"3"29;
"SRC"
$PN"2"6;
%"RES"
"1","(-7175,3100)","0","mstr_discrete","I342";
;
CDS_SEC"1"
MATERIAL"CHIP"
PART_NUMBER"G21796-072"
VALUE"4.75K"
TOLERANCE"1%"
PACK_TYPE"0402"
WATTAGE"1/16W"
LOCATION"R3N12"
SEC_TYPE"0402"
SEC"1"
BOM_COST"SM_CONTROLLER"
CDS_LIB"mstr_discrete"
CDS_LOCATION"R3N12"
ROOM"BMC_MISC";
"B"
$PN"2"25;
"A"
$PN"1"1;
%"RES"
"1","(-7175,2875)","0","mstr_discrete","I344";
;
CDS_SEC"1"
MATERIAL"CHIP"
PACK_TYPE"0402"
TOLERANCE"1%"
PART_NUMBER"G21796-072"
VALUE"4.75K"
WATTAGE"1/16W"
LOCATION"R3N11"
SEC_TYPE"0402"
SEC"1"
CDS_LIB"mstr_discrete"
BOM_COST"SM_CONTROLLER"
CDS_LOCATION"R3N11"
ROOM"BMC_MISC";
"B"
$PN"2"26;
"A"
$PN"1"1;
%"RES"
"1","(-7175,2650)","0","mstr_discrete","I346";
;
CDS_SEC"1"
LOCATION"R2M2"
MATERIAL"CHIP"
PACK_TYPE"0402"
TOLERANCE"1%"
PART_NUMBER"G21796-072"
VALUE"4.75K"
WATTAGE"1/16W"
SEC_TYPE"0402"
SEC"1"
BOM_COST"SM_CONTROLLER"
CDS_LIB"mstr_discrete"
CDS_LOCATION"R2M2"
ROOM"BMC_MISC";
"B"
$PN"2"20;
"A"
$PN"1"1;
%"RES"
"1","(-7175,2425)","0","mstr_discrete","I348";
;
CDS_SEC"1"
WATTAGE"1/16W"
MATERIAL"CHIP"
PACK_TYPE"0402"
TOLERANCE"1%"
VALUE"4.75K"
LOCATION"R2M5"
PART_NUMBER"G21796-072"
SEC"1"
SEC_TYPE"0402"
BOM_COST"SM_CONTROLLER"
ROOM"BMC_MISC"
CDS_LIB"mstr_discrete"
CDS_LOCATION"R2M5";
"B"
$PN"2"21;
"A"
$PN"1"1;
%"SWITCH_D90553001"
"1","(-4525,2675)","0","mstr_misc","I351";
;
CDS_SEC"1"
PART_NAME"SWITCH_D90553001"
PART_NUMBER"D90553-001"
MATERIAL"IC"
LOCATION"S8E1"
CDS_LIB"mstr_misc"
ROOM"MIO_CHASSIS"
CDS_LOCATION"S8E1"
SEC"1"
SEC_TYPE"SMLF"
BOM_COST"MIO_CHASSIS"
PACK_TYPE"SMLF";
"B \B"
$PN"2"34;
"A \B"
$PN"1"9;
%"RES"
"1","(-3675,2675)","0","mstr_discrete","I352";
;
CDS_SEC"1"
LOCATION"R2R9"
PACK_TYPE"0402"
WATTAGE"1/16W"
MATERIAL"CHIP"
VALUE"200.0"
TOLERANCE"1%"
PART_NUMBER"G21796-004"
SEC_TYPE"0402"
BOM_COST"MIO_CHASSIS"
SEC"1"
ROOM"MIO_CHASSIS"
CDS_LOCATION"R2R9"
CDS_LIB"mstr_discrete";
"B"
$PN"2"40;
"A"
$PN"1"34;
%"CAP_A"
"1","(-3225,2450)","0","dev_discrete","I353";
;
PACK_TYPE"0402V"
PART_NUMBER"D97712-004"
MATERIAL"X6S"
TOLERANCE"10%"
VOLTAGE"6.3V"
VALUE"1.0UF"
LOCATION"C2R12"
ROOM"MIO_CHASSIS"
SEC"1"
SEC_TYPE"0402V"
BOM_COST"MIO_CHASSIS"
CDS_SEC"1"
CDS_LIB"dev_discrete"
CDS_LOCATION"C2R12";
"B"
$PN"2"8;
"A"
$PN"1"40;
%"GND"
"1","(-3225,2175)","0","mstr_symbols","I354";
;
HDL_POWER"GND"
VOLTAGE"0.0V"
SIZE"1B"
CDS_LIB"mstr_symbols"
BODY_TYPE"PLUMBING";
"A\NAC"8;
%"GND"
"1","(-4925,2500)","0","mstr_symbols","I355";
;
VOLTAGE"0.0V"
CDS_LIB"mstr_symbols"
SIZE"1B"
BODY_TYPE"PLUMBING"
HDL_POWER"GND";
"A\NAC"9;
%"RES"
"1","(-7175,2200)","0","mstr_discrete","I361";
;
CDS_SEC"1"
LOCATION"R8E19"
WATTAGE"1/16W"
MATERIAL"EMPTY"
PACK_TYPE"0402"
TOLERANCE"1%"
PART_NUMBER"G21796-072"
VALUE"4.75K"
BOM_COST"SM_CONTROLLER"
SEC_TYPE"0402"
SEC"1"
ROOM"BMC_MISC"
CDS_LOCATION"R8E19"
CDS_LIB"mstr_discrete";
"B"
$PN"2"43;
"A"
$PN"1"1;
%"P3V3_STBY"
"1","(-5250,4675)","0","mstr_symbols","I362";
;
VOLTAGE"3.3V"
CDS_LIB"mstr_symbols"
SIZE"1B"
BODY_TYPE"PLUMBING"
HDL_POWER"P3V3_STBY";
"G\NAC"10;
%"RES"
"1","(-4925,4025)","0","mstr_discrete","I367";
;
CDS_SEC"1"
LOCATION"R2U4"
VALUE"4.75K"
MATERIAL"CHIP"
PACK_TYPE"0402"
TOLERANCE"1%"
WATTAGE"1/16W"
PART_NUMBER"G21796-072"
SEC_TYPE"0402"
BOM_COST"SM_CONTROLLER"
SEC"1"
ROOM"BMC_MISC"
CDS_LOCATION"R2U4"
CDS_LIB"mstr_discrete";
"B"
$PN"2"36;
"A"
$PN"1"10;
%"RES"
"1","(-6975,775)","0","mstr_discrete","I368";
;
CDS_SEC"1"
TOLERANCE"1%"
MATERIAL"CHIP"
PART_NUMBER"G21796-026"
WATTAGE"1/16W"
VALUE"1.00K"
LOCATION"R4R1"
PACK_TYPE"0402"
CDS_LIB"mstr_discrete"
SEC_TYPE"0402"
SEC"1"
CDS_LOCATION"R4R1"
ROOM"MIO_CHASSIS"
BOM_COST"MIO_CHASSIS";
"B"
$PN"2"27;
"A"
$PN"1"41;
%"P3V3_STBY"
"1","(-1700,2825)","0","mstr_symbols","I369";
;
HDL_POWER"P3V3_STBY"
VOLTAGE"3.3V"
CDS_LIB"mstr_symbols"
BODY_TYPE"PLUMBING"
SIZE"1B";
"G\NAC"11;
%"CAP_A"
"1","(-1700,2575)","0","dev_discrete","I370";
;
PART_NUMBER"A36096-030"
MATERIAL"X7R"
VOLTAGE"16V"
PACK_TYPE"0402V"
TOLERANCE"10%"
VALUE"0.1UF"
LOCATION"C2T3"
SEC"1"
SEC_TYPE"0402V"
CDS_SEC"1"
BOM_COST"MIO_CHASSIS"
ROOM"MIO_CHASSIS"
CDS_LOCATION"C2T3"
CDS_LIB"dev_discrete";
"B"
$PN"2"12;
"A"
$PN"1"11;
%"GND"
"1","(-1700,2375)","0","mstr_symbols","I371";
;
CDS_LIB"mstr_symbols"
VOLTAGE"0.0V"
HDL_POWER"GND"
BODY_TYPE"PLUMBING"
SIZE"1B";
"A\NAC"12;
%"TTL1G07_A"
"1","(-2800,1150)","0","mstr_ttl","I374";
;
CDS_SEC"1"
POWER_GROUP"VCC=P3V3_STBY;GND=GND"
PART_NUMBER"C88419-001"
LOCATION"U8D2"
MATERIAL"IC"
VALUE"74LVC1G07"
CDS_LOCATION"U8D2"
SEC"1"
SEC_TYPE"SOP"
PACK_TYPE"SOP"
CDS_LIB"mstr_ttl";
"Y"
$PN"4"19;
"A"
$PN"2"30;
%"CAP_A"
"1","(-500,1750)","0","dev_discrete","I376";
;
LOCATION"C8D1"
VALUE"0.1UF"
VOLTAGE"16V"
TOLERANCE"10%"
MATERIAL"X7R"
PART_NUMBER"A36096-030"
PACK_TYPE"0402V"
CDS_LIB"dev_discrete"
CDS_SEC"1"
CDS_LOCATION"C8D1"
SEC"1"
SEC_TYPE"0402V";
"B"
$PN"2"13;
"A"
$PN"1"14;
%"GND"
"1","(-500,1575)","0","mstr_symbols","I377";
;
BODY_TYPE"PLUMBING"
VOLTAGE"0.0V"
SIZE"1B"
CDS_LIB"mstr_symbols"
HDL_POWER"GND";
"A\NAC"13;
%"P3V3_STBY"
"1","(-500,1950)","0","mstr_symbols","I378";
;
CDS_LIB"mstr_symbols"
SIZE"1B"
VOLTAGE"3.3V"
BODY_TYPE"PLUMBING"
HDL_POWER"P3V3_STBY";
"G\NAC"14;
%"RES"
"1","(-7175,3425)","0","mstr_discrete","I382";
;
CDS_SEC"1"
TOLERANCE"1%"
PART_NUMBER"G21796-072"
VALUE"4.75K"
PACK_TYPE"0402"
MATERIAL"CHIP"
WATTAGE"1/16W"
LOCATION"R1L7"
SEC_TYPE"0402"
SEC"1"
BOM_COST"SM_CONTROLLER"
ROOM"BMC_MISC"
CDS_LIB"mstr_discrete"
CDS_LOCATION"R1L7";
"B"
$PN"2"22;
"A"
$PN"1"1;
%"P3V3_STBY"
"1","(-3975,3225)","0","mstr_symbols","I384";
;
VOLTAGE"3.3V"
CDS_LIB"mstr_symbols"
SIZE"1B"
BODY_TYPE"PLUMBING"
HDL_POWER"P3V3_STBY";
"G\NAC"15;
%"RES"
"2","(-3975,2950)","0","mstr_discrete","I385";
;
CDS_SEC"1"
PACK_TYPE"0402"
PART_NUMBER"G21796-072"
MATERIAL"CHIP"
WATTAGE"1/16W"
TOLERANCE"1%"
VALUE"4.75K"
LOCATION"R8E32"
BOM_COST"MIO_CHASSIS"
SEC_TYPE"0402"
SEC"1"
ROOM"MIO_CHASSIS"
CDS_LIB"mstr_discrete"
CDS_LOCATION"R8E32";
"A"
$PN"1"15;
"B"
$PN"2"34;
%"RES"
"1","(-1925,1150)","0","mstr_discrete","I386";
;
CDS_SEC"1"
PART_NUMBER"G21796-074"
LOCATION"R8D22"
PACK_TYPE"0402"
MATERIAL"CHIP"
TOLERANCE"1%"
VALUE"33.2"
WATTAGE"1/16W"
ROOM"BMC_MISC"
SEC"1"
BOM_COST"SM"
SEC_TYPE"0402"
CDS_LOCATION"R8D22"
CDS_LIB"mstr_discrete";
"B"
$PN"2"32;
"A"
$PN"1"19;
%"RES"
"1","(-1425,1375)","0","mstr_discrete","I388";
;
CDS_SEC"1"
CDS_LOCATION"R8D36"
POP"NOPOP"
PACK_TYPE"0402"
PART_NUMBER"G21796-074"
LOCATION"R8D36"
MATERIAL"CHIP"
WATTAGE"1/16W"
VALUE"33.2"
TOLERANCE"1%"
ROOM"BMC_MISC"
SEC"1"
BOM_COST"SM"
SEC_TYPE"0402"
CDS_LIB"mstr_discrete";
"B"
$PN"2"18;
"A"
$PN"1"19;
%"TC7PZ14FU-GP"
"1","(-2425,2725)","0","w_hdl","I390";
;
CDS_SEC"1"
CDS_LOCATION"U2R1"
VALUE"TC7PZ14FU-GP"
LOCATION"U2R1"
PACK_TYPE"DISCRET-GA1"
PART_NUMBER"073.7PZ14.0007"
SEC"1"
SEC_TYPE"DISCRET-GA1"
CDS_LIB"w_hdl"
CDS_LMAN_SYM_OUTLINE"-200,150,200,-150";
"1Y"
$PN"6"35;
"VCC"
$PN"5"11;
"2Y"
$PN"4"33;
"2A"
$PN"3"40;
"GND"
$PN"2"16;
"1A"
$PN"1"33;
%"RES"
"1","(-1250,2925)","0","mstr_discrete","I391";
;
PACK_TYPE"0402"
WATTAGE"1/16W"
MATERIAL"CHIP"
TOLERANCE"1%"
VALUE"33.2"
PART_NUMBER"G21796-074"
LOCATION"R2R10"
ROOM"MIO_CHASSIS"
SEC"1"
BOM_COST"MIO_CHASSIS"
SEC_TYPE"0402"
CDS_LIB"mstr_discrete"
CDS_LOCATION"R2R10"
CDS_SEC"1";
"B"
$PN"2"38;
"A"
$PN"1"35;
%"GND"
"1","(-3050,2750)","0","mstr_symbols","I392";
;
CDS_LIB"mstr_symbols"
VOLTAGE"0.0V"
HDL_POWER"GND"
BODY_TYPE"PLUMBING"
SIZE"1B";
"A\NAC"16;
%"RES"
"1","(-1450,875)","0","mstr_discrete","I393";
;
CDS_SEC"1"
LOCATION"R9E14"
TOLERANCE"5%"
MATERIAL"EMPTY"
PACK_TYPE"0402"
WATTAGE"1/16W"
VALUE"0.0"
PART_NUMBER"G21497-005"
CDS_LOCATION"R9E14"
BOM_COST"MEM_NV"
SEC_TYPE"0402"
ROOM"NV_DIMM"
SEC"1"
CDS_LIB"mstr_discrete";
"B"
$PN"2"39;
"A"
$PN"1"32;
%"TTL1G07_A"
"1","(-2800,500)","0","mstr_ttl","I394";
;
CDS_SEC"1"
LOCATION"U25W9"
VALUE"74LVC1G07"
MATERIAL"IC"
POWER_GROUP"VCC=P3V3_STBY;GND=GND"
PART_NUMBER"C88419-001"
CDS_LOCATION"U25W9"
CDS_LIB"mstr_ttl"
PACK_TYPE"SOP"
SEC_TYPE"SOP"
SEC"1";
"Y"
$PN"4"31;
"A"
$PN"2"30;
%"P3V3_STBY"
"1","(-2275,900)","0","mstr_symbols","I395";
;
HDL_POWER"P3V3_STBY"
VOLTAGE"3.3V"
BODY_TYPE"PLUMBING"
CDS_LIB"mstr_symbols"
SIZE"1B";
"G\NAC"17;
%"RES"
"2","(-2275,700)","0","mstr_discrete","I396";
;
CDS_SEC"1"
WATTAGE"1/16W"
PACK_TYPE"0402"
PART_NUMBER"G21796-072"
MATERIAL"CHIP"
TOLERANCE"1%"
VALUE"4.75K"
LOCATION"R25W153"
CDS_LOCATION"R25W153"
CDS_LIB"mstr_discrete"
SEC"1"
SEC_TYPE"0402"
ROOM"BMC_MISC"
BOM_COST"SM_CONTROLLER";
"A"
$PN"1"17;
"B"
$PN"2"31;
%"RES"
"2","(-1850,4025)","0","mstr_discrete","I97";
;
CDS_SEC"1"
PACK_TYPE"0402"
PART_NUMBER"G21796-072"
MATERIAL"CHIP"
WATTAGE"1/16W"
VALUE"4.75K"
TOLERANCE"1%"
LOCATION"R2N27"
SEC"1"
SEC_TYPE"0402"
ROOM"BMC_MISC"
BOM_COST"SM_CONTROLLER"
CDS_LOCATION"R2N27"
CDS_LIB"mstr_discrete";
"A"
$PN"1"2;
"B"
$PN"2"37;
END.
